FILE_TYPE = MACRO_DRAWING;
SET COLOR_WIRE YELLOW;
SET COLOR_PROP MONO;
SET COLOR_DOT WHITE;
SET COLOR_ARC YELLOW;
SET COLOR_BODY GREEN;
SET COLOR_NOTE MONO;
SET PROP_DISPLAY VALUE;
SET PAGE_NUMBER P179;
FORCEADD INTEL_CORP_BPAGE..1
(4250 200);
FORCEPROP 1 LAST CUSTOM_TXT_CDS <CURRENT_DESIGN_SHEET> OF <TOTAL_DESIGN_SHEETS>
J 0
(3750 225);
PAINT GREEN (3750 225);
FORCEPROP 1 LAST CUSTOM_TXT_CDS <CON_LAST_MODIFIED>
J 0
(2325 550);
PAINT GREEN (2325 550);
FORCEPROP 2 LAST CUSTOM_TXT_CDS <XR_PAGE_TITLE>
J 0
(-3640 5450);
DISPLAY 0.638298 (-3640 5450);
PAINT PINK (-3640 5450);
DISPLAY INVISIBLE (-3640 5450);
FORCEPROP 1 LAST SCH_ADDRESS3 Santa Clara, CA 95052-8119
J 0
(275 225);
DISPLAY 0.617021 (275 225);
PAINT YELLOW (275 225);
FORCEPROP 1 LAST SCH_ADDRESS2 P.O. BOX 58119
J 0
(275 275);
DISPLAY 0.617021 (275 275);
PAINT YELLOW (275 275);
FORCEPROP 1 LAST SCH_ADDRESS1 2200 Mission College Blvd.
J 0
(275 325);
DISPLAY 0.617021 (275 325);
PAINT YELLOW (275 325);
FORCEPROP 1 LAST SCH_TITLE SPARE
J 0
(-3700 250);
DISPLAY 1.212766 (-3700 250);
PAINT YELLOW (-3700 250);
FORCEPROP 1 LAST SCH_NUMBER H4694802
J 0
(2950 350);
DISPLAY 1.212766 (2950 350);
PAINT YELLOW (2950 350);
FORCEPROP 1 LAST SCH_DEPT BESD
J 1
(-200 300);
DISPLAY 1.212766 (-200 300);
PAINT YELLOW (-200 300);
FORCEPROP 1 LAST SCH_REV 2.420
J 0
(4000 350);
DISPLAY 0.978723 (4000 350);
PAINT YELLOW (4000 350);
FORCEPROP 2 LAST PAGE_BORDER TRUE
J 0
(-3640 5450);
DISPLAY 0.638298 (-3640 5450);
PAINT PINK (-3640 5450);
DISPLAY INVISIBLE (-3640 5450);
FORCEPROP 2 LAST CDS_LIB mstr_symbols
J 0
(4250 200);
PAINT MONO (4250 200);
DISPLAY INVISIBLE (4250 200);
FORCEPROP 1 LAST COMMENT_BODY TRUE
J 0
(4262 212);
DISPLAY 0.468085 (4262 212);
PAINT PEACH (4262 212);
DISPLAY INVISIBLE (4262 212);
FORCEPROP 1 LAST CDS_CON_LAST_MODIFIED Tue Dec 01 11:48:55 2015
J 0
(2825 525);
PAINT ORANGE (2825 525);
DISPLAY INVISIBLE (2825 525);
FORCEPROP 2 LAST CDS_XR_PAGE_TITLE CR-179 : @BASEBOARD_FAB2_LIB.BASEBOARD_FAB2(SCH_1):PAGE179
J 0
(-3640 5450);
DISPLAY 0.638298 (-3640 5450);
PAINT PINK (-3640 5450);
DISPLAY INVISIBLE (-3640 5450);
QUIT
